(kicad_pcb
	(version 20241229)
	(generator "pcbnew")
	(generator_version "9.0")
	(general
		(thickness 1.6296)
		(legacy_teardrops no)
	)
	(paper "A3")
	(title_block
		(title "Thunderbolt to 10GbE adapter")
		(date "2026-04-21")
		(rev "1.1.0")
		(company "Antmicro Ltd")
		(comment 1 "www.antmicro.com")
		(comment 9 "footprints 630-634 of 703")
	)
	(layers
		(0 "F.Cu" signal)
		(4 "In1.Cu" signal)
		(6 "In2.Cu" signal)
		(8 "In3.Cu" signal)
		(10 "In4.Cu" signal)
		(12 "In5.Cu" signal)
		(14 "In6.Cu" signal)
		(2 "B.Cu" signal)
		(9 "F.Adhes" user "F.Adhesive")
		(11 "B.Adhes" user "B.Adhesive")
		(13 "F.Paste" user)
		(15 "B.Paste" user)
		(5 "F.SilkS" user "F.Silkscreen")
		(7 "B.SilkS" user "B.Silkscreen")
		(1 "F.Mask" user)
		(3 "B.Mask" user)
		(17 "Dwgs.User" user "User.Drawings")
		(19 "Cmts.User" user "User.Comments")
		(21 "Eco1.User" user "User.Eco1")
		(23 "Eco2.User" user "User.Eco2")
		(25 "Edge.Cuts" user)
		(27 "Margin" user)
		(31 "F.CrtYd" user "F.Courtyard")
		(29 "B.CrtYd" user "B.Courtyard")
		(35 "F.Fab" user)
		(33 "B.Fab" user)
	)
	(footprint "antmicro-footprints:C_0402_1005Metric"
		(layer "B.Cu")
		(at 153.031866 80.260117 180)
		(descr "Capacitor SMD 0402")
		(tags "capacitor SMD 0402")
		(property "Reference" "C264"
			(at -21.168135 -9.464883 0)
			(layer "B.SilkS")
			(effects
				(font
					(size 0.7 0.7)
					(thickness 0.15)
				)
				(justify mirror)
			)
		)
		(property "Value" "C_1u_25V_0402"
			(at -1.022927 -2.155213 0)
			(layer "B.Fab")
			(effects
				(font
					(size 0.7 0.7)
					(thickness 0.15)
				)
				(justify left bottom mirror)
			)
		)
		(property "Datasheet" "https://www.murata.com/products/productdetail?partno=GRM155R61E105KE11%23"
			(at 0 0 0)
			(layer "B.Fab")
			(hide yes)
			(effects
				(font
					(size 1.27 1.27)
					(thickness 0.15)
				)
				(justify mirror)
			)
		)
		(property "Description" "SMD Multilayer Ceramic Capacitor, 1 µF, 25 V, 0402 [1005 Metric], ± 10%, X5R, GRM Series"
			(at 0 0 0)
			(layer "B.Fab")
			(hide yes)
			(effects
				(font
					(size 1.27 1.27)
					(thickness 0.15)
				)
				(justify mirror)
			)
		)
		(property "MPN" "GRM155R61E105KE11J"
			(at 0 0 180)
			(unlocked yes)
			(layer "B.Fab")
			(hide yes)
			(effects
				(font
					(size 1 1)
					(thickness 0.15)
				)
				(justify mirror)
			)
		)
		(property "Manufacturer" "Murata"
			(at 0 0 180)
			(unlocked yes)
			(layer "B.Fab")
			(hide yes)
			(effects
				(font
					(size 1 1)
					(thickness 0.15)
				)
				(justify mirror)
			)
		)
		(property "License" "Apache-2.0"
			(at 0 0 180)
			(unlocked yes)
			(layer "B.Fab")
			(hide yes)
			(effects
				(font
					(size 1 1)
					(thickness 0.15)
				)
				(justify mirror)
			)
		)
		(property "Author" "Antmicro"
			(at 0 0 180)
			(unlocked yes)
			(layer "B.Fab")
			(hide yes)
			(effects
				(font
					(size 1 1)
					(thickness 0.15)
				)
				(justify mirror)
			)
		)
		(property "Val" "1u"
			(at 0 0 180)
			(unlocked yes)
			(layer "B.Fab")
			(hide yes)
			(effects
				(font
					(size 1 1)
					(thickness 0.15)
				)
				(justify mirror)
			)
		)
		(property "Voltage" "25V"
			(at 0 0 180)
			(unlocked yes)
			(layer "B.Fab")
			(hide yes)
			(effects
				(font
					(size 1 1)
					(thickness 0.15)
				)
				(justify mirror)
			)
		)
		(property "Dielectric" "X5R"
			(at 0 0 180)
			(unlocked yes)
			(layer "B.Fab")
			(hide yes)
			(effects
				(font
					(size 1 1)
					(thickness 0.15)
				)
				(justify mirror)
			)
		)
		(sheetname "/X710-AT2 power/")
		(sheetfile "x710-at2-power.kicad_sch")
		(attr smd)
		(fp_rect
			(start -0.925 0.47)
			(end 0.925 -0.47)
			(stroke
				(width 0.05)
				(type default)
			)
			(fill no)
			(layer "B.CrtYd")
		)
		(fp_line
			(start 0.504 0.25)
			(end 0.504 -0.248)
			(stroke
				(width 0.15)
				(type solid)
			)
			(layer "B.Fab")
		)
		(fp_line
			(start 0.504 -0.248)
			(end -0.494 -0.248)
			(stroke
				(width 0.15)
				(type solid)
			)
			(layer "B.Fab")
		)
		(fp_line
			(start -0.494 0.25)
			(end 0.504 0.25)
			(stroke
				(width 0.15)
				(type solid)
			)
			(layer "B.Fab")
		)
		(fp_line
			(start -0.494 -0.248)
			(end -0.494 0.25)
			(stroke
				(width 0.15)
				(type solid)
			)
			(layer "B.Fab")
		)
		(fp_text user "Author: Antmicro"
			(at -0.939 -3.399 0)
			(layer "B.Fab")
			(effects
				(font
					(size 0.7 0.7)
					(thickness 0.15)
				)
				(justify left bottom mirror)
			)
		)
		(fp_text user "${REFERENCE}"
			(at -0.939 -4.599 0)
			(layer "B.Fab")
			(effects
				(font
					(size 0.7 0.7)
					(thickness 0.15)
				)
				(justify left bottom mirror)
			)
		)
		(fp_text user "License: Apache-2.0"
			(at -0.939 -5.799 0)
			(layer "B.Fab")
			(effects
				(font
					(size 0.7 0.7)
					(thickness 0.15)
				)
				(justify left bottom mirror)
			)
		)
		(pad "1" smd roundrect
			(at -0.48 0 180)
			(size 0.59 0.64)
			(layers "B.Cu" "B.Mask" "B.Paste")
			(roundrect_rratio 0.25)
			(net 23 "GND")
			(pintype "passive")
		)
		(pad "2" smd roundrect
			(at 0.48 0 180)
			(size 0.59 0.64)
			(layers "B.Cu" "B.Mask" "B.Paste")
			(roundrect_rratio 0.25)
			(net 9 "VCCD")
			(pintype "passive")
		)
	)
	(footprint "antmicro-footprints:R_0402_1005Metric"
		(layer "B.Cu")
		(at 122.75 127.025)
		(descr "Resistor SMD 0402")
		(tags "resistor SMD 0402")
		(property "Reference" "R56"
			(at -2.25 0 180)
			(layer "B.SilkS")
			(effects
				(font
					(size 0.7 0.7)
					(thickness 0.15)
				)
				(justify mirror)
			)
		)
		(property "Value" "R_499R_0402"
			(at -1.011843 -1.772047 180)
			(layer "B.Fab")
			(effects
				(font
					(size 0.7 0.7)
					(thickness 0.15)
				)
				(justify left bottom mirror)
			)
		)
		(property "Datasheet" "https://www.mouser.com/datasheet/2/54/cr-1858361.pdf"
			(at 0 0 180)
			(layer "B.Fab")
			(hide yes)
			(effects
				(font
					(size 1.27 1.27)
					(thickness 0.15)
				)
				(justify mirror)
			)
		)
		(property "Description" "SMD Chip Resistor, 499 ohm, ± 1%, 63 mW, 0402 [1005 Metric], Thick Film, General Purpose"
			(at 0 0 180)
			(layer "B.Fab")
			(hide yes)
			(effects
				(font
					(size 1.27 1.27)
					(thickness 0.15)
				)
				(justify mirror)
			)
		)
		(property "MPN" "CR0402-FX-4990GLF"
			(at 0 0 0)
			(unlocked yes)
			(layer "B.Fab")
			(hide yes)
			(effects
				(font
					(size 1 1)
					(thickness 0.15)
				)
				(justify mirror)
			)
		)
		(property "Manufacturer" "Bourns"
			(at 0 0 0)
			(unlocked yes)
			(layer "B.Fab")
			(hide yes)
			(effects
				(font
					(size 1 1)
					(thickness 0.15)
				)
				(justify mirror)
			)
		)
		(property "License" "Apache-2.0"
			(at 0 0 0)
			(unlocked yes)
			(layer "B.Fab")
			(hide yes)
			(effects
				(font
					(size 1 1)
					(thickness 0.15)
				)
				(justify mirror)
			)
		)
		(property "Val" "499R"
			(at 0 0 0)
			(unlocked yes)
			(layer "B.Fab")
			(hide yes)
			(effects
				(font
					(size 1 1)
					(thickness 0.15)
				)
				(justify mirror)
			)
		)
		(property "Tolerance" "1%"
			(at 0 0 0)
			(unlocked yes)
			(layer "B.Fab")
			(hide yes)
			(effects
				(font
					(size 1 1)
					(thickness 0.15)
				)
				(justify mirror)
			)
		)
		(property "Author" "Antmicro"
			(at 0 0 0)
			(unlocked yes)
			(layer "B.Fab")
			(hide yes)
			(effects
				(font
					(size 1 1)
					(thickness 0.15)
				)
				(justify mirror)
			)
		)
		(sheetname "/TB Controller/")
		(sheetfile "tb.kicad_sch")
		(attr smd)
		(fp_rect
			(start -0.925 0.47)
			(end 0.925 -0.47)
			(stroke
				(width 0.05)
				(type default)
			)
			(fill no)
			(layer "B.CrtYd")
		)
		(fp_rect
			(start -0.5 0.25)
			(end 0.5 -0.25)
			(stroke
				(width 0.15)
				(type solid)
			)
			(fill no)
			(layer "B.Fab")
		)
		(fp_text user "Author: Antmicro"
			(at -0.95 -4.169 180)
			(layer "B.Fab")
			(effects
				(font
					(size 0.7 0.7)
					(thickness 0.15)
				)
				(justify left bottom mirror)
			)
		)
		(fp_text user "License: Apache-2.0"
			(at -0.95 -5.169 180)
			(layer "B.Fab")
			(effects
				(font
					(size 0.7 0.7)
					(thickness 0.15)
				)
				(justify left bottom mirror)
			)
		)
		(fp_text user "${REFERENCE}"
			(at -0.95 -3.168 180)
			(layer "B.Fab")
			(effects
				(font
					(size 0.7 0.7)
					(thickness 0.15)
				)
				(justify left bottom mirror)
			)
		)
		(pad "1" smd roundrect
			(at -0.48 0)
			(size 0.59 0.64)
			(layers "B.Cu" "B.Mask" "B.Paste")
			(roundrect_rratio 0.25)
			(net 23 "GND")
			(pintype "passive")
		)
		(pad "2" smd roundrect
			(at 0.48 0)
			(size 0.59 0.64)
			(layers "B.Cu" "B.Mask" "B.Paste")
			(roundrect_rratio 0.25)
			(net 228 "Net-(U4E-PA_USB2_RBIAS)")
			(pintype "passive")
		)
	)
	(footprint "antmicro-footprints:R_0402_1005Metric"
		(layer "B.Cu")
		(at 136.5 124.15)
		(descr "Resistor SMD 0402")
		(tags "resistor SMD 0402")
		(property "Reference" "R68"
			(at 19.525001 -7.450001 180)
			(layer "B.SilkS")
			(effects
				(font
					(size 0.7 0.7)
					(thickness 0.15)
				)
				(justify mirror)
			)
		)
		(property "Value" "R_100R_0402"
			(at -1.011843 -1.772047 180)
			(layer "B.Fab")
			(effects
				(font
					(size 0.7 0.7)
					(thickness 0.15)
				)
				(justify left bottom mirror)
			)
		)
		(property "Datasheet" "https://www.bourns.com/docs/product-datasheets/cr.pdf"
			(at 0 0 180)
			(layer "B.Fab")
			(hide yes)
			(effects
				(font
					(size 1.27 1.27)
					(thickness 0.15)
				)
				(justify mirror)
			)
		)
		(property "Description" "SMD Chip Resistor, 100 ohm, ± 1%, 62.5 mW, 0402 [1005 Metric], Thick Film, General Purpose"
			(at 0 0 180)
			(layer "B.Fab")
			(hide yes)
			(effects
				(font
					(size 1.27 1.27)
					(thickness 0.15)
				)
				(justify mirror)
			)
		)
		(property "MPN" "CR0402-FX-1000GLF"
			(at 0 0 0)
			(unlocked yes)
			(layer "B.Fab")
			(hide yes)
			(effects
				(font
					(size 1 1)
					(thickness 0.15)
				)
				(justify mirror)
			)
		)
		(property "Manufacturer" "Bourns"
			(at 0 0 0)
			(unlocked yes)
			(layer "B.Fab")
			(hide yes)
			(effects
				(font
					(size 1 1)
					(thickness 0.15)
				)
				(justify mirror)
			)
		)
		(property "License" "Apache-2.0"
			(at 0 0 0)
			(unlocked yes)
			(layer "B.Fab")
			(hide yes)
			(effects
				(font
					(size 1 1)
					(thickness 0.15)
				)
				(justify mirror)
			)
		)
		(property "Val" "100R"
			(at 0 0 0)
			(unlocked yes)
			(layer "B.Fab")
			(hide yes)
			(effects
				(font
					(size 1 1)
					(thickness 0.15)
				)
				(justify mirror)
			)
		)
		(property "Tolerance" "1%"
			(at 0 0 0)
			(unlocked yes)
			(layer "B.Fab")
			(hide yes)
			(effects
				(font
					(size 1 1)
					(thickness 0.15)
				)
				(justify mirror)
			)
		)
		(property "Author" "Antmicro"
			(at 0 0 0)
			(unlocked yes)
			(layer "B.Fab")
			(hide yes)
			(effects
				(font
					(size 1 1)
					(thickness 0.15)
				)
				(justify mirror)
			)
		)
		(sheetname "/TB Controller/")
		(sheetfile "tb.kicad_sch")
		(attr smd)
		(fp_rect
			(start -0.925 0.47)
			(end 0.925 -0.47)
			(stroke
				(width 0.05)
				(type default)
			)
			(fill no)
			(layer "B.CrtYd")
		)
		(fp_rect
			(start -0.5 0.25)
			(end 0.5 -0.25)
			(stroke
				(width 0.15)
				(type solid)
			)
			(fill no)
			(layer "B.Fab")
		)
		(fp_text user "License: Apache-2.0"
			(at -0.95 -5.169 180)
			(layer "B.Fab")
			(effects
				(font
					(size 0.7 0.7)
					(thickness 0.15)
				)
				(justify left bottom mirror)
			)
		)
		(fp_text user "Author: Antmicro"
			(at -0.95 -4.169 180)
			(layer "B.Fab")
			(effects
				(font
					(size 0.7 0.7)
					(thickness 0.15)
				)
				(justify left bottom mirror)
			)
		)
		(fp_text user "${REFERENCE}"
			(at -0.95 -3.168 180)
			(layer "B.Fab")
			(effects
				(font
					(size 0.7 0.7)
					(thickness 0.15)
				)
				(justify left bottom mirror)
			)
		)
		(pad "1" smd roundrect
			(at -0.48 0)
			(size 0.59 0.64)
			(layers "B.Cu" "B.Mask" "B.Paste")
			(roundrect_rratio 0.25)
			(net 237 "Net-(U4D-TEST_EN)")
			(pintype "passive")
		)
		(pad "2" smd roundrect
			(at 0.48 0)
			(size 0.59 0.64)
			(layers "B.Cu" "B.Mask" "B.Paste")
			(roundrect_rratio 0.25)
			(net 23 "GND")
			(pintype "passive")
		)
	)
	(footprint "antmicro-footprints:C_0402_1005Metric"
		(layer "B.Cu")
		(at 128.499999 120.050001 -90)
		(descr "Capacitor SMD 0402")
		(tags "capacitor SMD 0402")
		(property "Reference" "C54"
			(at -7.700002 -21.900002 90)
			(layer "B.SilkS")
			(effects
				(font
					(size 0.7 0.7)
					(thickness 0.15)
				)
				(justify mirror)
			)
		)
		(property "Value" "C_1u_0402"
			(at -1.022927 -2.155213 90)
			(layer "B.Fab")
			(effects
				(font
					(size 0.7 0.7)
					(thickness 0.15)
				)
				(justify left bottom mirror)
			)
		)
		(property "Datasheet" "https://product.tdk.com/en/search/capacitor/ceramic/mlcc/info?part_no=C1005X6S1A105K050BC"
			(at 0 0 90)
			(layer "B.Fab")
			(hide yes)
			(effects
				(font
					(size 1.27 1.27)
					(thickness 0.15)
				)
				(justify mirror)
			)
		)
		(property "Description" "SMD Multilayer Ceramic Capacitor, 1 µF, 10 V, 0402 [1005 Metric], ± 10%, X6S, C"
			(at 0 0 90)
			(layer "B.Fab")
			(hide yes)
			(effects
				(font
					(size 1.27 1.27)
					(thickness 0.15)
				)
				(justify mirror)
			)
		)
		(property "MPN" "C1005X6S1A105K050BC"
			(at 0 0 270)
			(unlocked yes)
			(layer "B.Fab")
			(hide yes)
			(effects
				(font
					(size 1 1)
					(thickness 0.15)
				)
				(justify mirror)
			)
		)
		(property "Manufacturer" "TDK"
			(at 0 0 270)
			(unlocked yes)
			(layer "B.Fab")
			(hide yes)
			(effects
				(font
					(size 1 1)
					(thickness 0.15)
				)
				(justify mirror)
			)
		)
		(property "License" "Apache-2.0"
			(at 0 0 270)
			(unlocked yes)
			(layer "B.Fab")
			(hide yes)
			(effects
				(font
					(size 1 1)
					(thickness 0.15)
				)
				(justify mirror)
			)
		)
		(property "Val" "1u"
			(at 0 0 270)
			(unlocked yes)
			(layer "B.Fab")
			(hide yes)
			(effects
				(font
					(size 1 1)
					(thickness 0.15)
				)
				(justify mirror)
			)
		)
		(property "Voltage" ""
			(at 0 0 270)
			(unlocked yes)
			(layer "B.Fab")
			(hide yes)
			(effects
				(font
					(size 1 1)
					(thickness 0.15)
				)
				(justify mirror)
			)
		)
		(property "Dielectric" ""
			(at 0 0 270)
			(unlocked yes)
			(layer "B.Fab")
			(hide yes)
			(effects
				(font
					(size 1 1)
					(thickness 0.15)
				)
				(justify mirror)
			)
		)
		(property "Author" "Antmicro"
			(at 0 0 270)
			(unlocked yes)
			(layer "B.Fab")
			(hide yes)
			(effects
				(font
					(size 1 1)
					(thickness 0.15)
				)
				(justify mirror)
			)
		)
		(sheetname "/TB Controller - Power/")
		(sheetfile "tb-power.kicad_sch")
		(attr smd)
		(fp_rect
			(start -0.925 0.47)
			(end 0.925 -0.47)
			(stroke
				(width 0.05)
				(type default)
			)
			(fill no)
			(layer "B.CrtYd")
		)
		(fp_line
			(start -0.494 0.25)
			(end 0.504 0.25)
			(stroke
				(width 0.15)
				(type solid)
			)
			(layer "B.Fab")
		)
		(fp_line
			(start 0.504 0.25)
			(end 0.504 -0.248)
			(stroke
				(width 0.15)
				(type solid)
			)
			(layer "B.Fab")
		)
		(fp_line
			(start -0.494 -0.248)
			(end -0.494 0.25)
			(stroke
				(width 0.15)
				(type solid)
			)
			(layer "B.Fab")
		)
		(fp_line
			(start 0.504 -0.248)
			(end -0.494 -0.248)
			(stroke
				(width 0.15)
				(type solid)
			)
			(layer "B.Fab")
		)
		(fp_text user "Author: Antmicro"
			(at -0.939 -3.399 90)
			(layer "B.Fab")
			(effects
				(font
					(size 0.7 0.7)
					(thickness 0.15)
				)
				(justify left bottom mirror)
			)
		)
		(fp_text user "License: Apache-2.0"
			(at -0.939 -5.799 90)
			(layer "B.Fab")
			(effects
				(font
					(size 0.7 0.7)
					(thickness 0.15)
				)
				(justify left bottom mirror)
			)
		)
		(fp_text user "${REFERENCE}"
			(at -0.939 -4.599 90)
			(layer "B.Fab")
			(effects
				(font
					(size 0.7 0.7)
					(thickness 0.15)
				)
				(justify left bottom mirror)
			)
		)
		(pad "1" smd roundrect
			(at -0.48 0 270)
			(size 0.59 0.64)
			(layers "B.Cu" "B.Mask" "B.Paste")
			(roundrect_rratio 0.25)
			(net 23 "GND")
			(pintype "passive")
		)
		(pad "2" smd roundrect
			(at 0.48 0 270)
			(size 0.59 0.64)
			(layers "B.Cu" "B.Mask" "B.Paste")
			(roundrect_rratio 0.25)
			(net 402 "Net-(C52-Pad2)")
			(pintype "passive")
		)
	)
	(footprint "antmicro-footprints:R_0402_1005Metric"
		(layer "B.Cu")
		(at 176.58 146.66 90)
		(descr "Resistor SMD 0402")
		(tags "resistor SMD 0402")
		(property "Reference" "R213"
			(at -1.09 0.42 270)
			(layer "B.SilkS")
			(effects
				(font
					(size 0.7 0.7)
					(thickness 0.15)
				)
				(justify left bottom mirror)
			)
		)
		(property "Value" "R_220R_0402"
			(at -1.011843 -1.772047 270)
			(layer "B.Fab")
			(effects
				(font
					(size 0.7 0.7)
					(thickness 0.15)
				)
				(justify left bottom mirror)
			)
		)
		(property "Datasheet" "https://www.bourns.com/docs/product-datasheets/cr.pdf"
			(at 0 0 270)
			(layer "B.Fab")
			(hide yes)
			(effects
				(font
					(size 1.27 1.27)
					(thickness 0.15)
				)
				(justify mirror)
			)
		)
		(property "Description" "SMD Chip Resistor, 220 ohm, ± 1%, 62.5 mW, 0402 [1005 Metric], Thick Film, General Purpose"
			(at 0 0 270)
			(layer "B.Fab")
			(hide yes)
			(effects
				(font
					(size 1.27 1.27)
					(thickness 0.15)
				)
				(justify mirror)
			)
		)
		(property "MPN" "CR0402-FX-2200GLF"
			(at 0 0 90)
			(unlocked yes)
			(layer "B.Fab")
			(hide yes)
			(effects
				(font
					(size 1 1)
					(thickness 0.15)
				)
				(justify mirror)
			)
		)
		(property "Manufacturer" "Bourns"
			(at 0 0 90)
			(unlocked yes)
			(layer "B.Fab")
			(hide yes)
			(effects
				(font
					(size 1 1)
					(thickness 0.15)
				)
				(justify mirror)
			)
		)
		(property "License" "Apache-2.0"
			(at 0 0 90)
			(unlocked yes)
			(layer "B.Fab")
			(hide yes)
			(effects
				(font
					(size 1 1)
					(thickness 0.15)
				)
				(justify mirror)
			)
		)
		(property "Author" "Antmicro"
			(at 0 0 90)
			(unlocked yes)
			(layer "B.Fab")
			(hide yes)
			(effects
				(font
					(size 1 1)
					(thickness 0.15)
				)
				(justify mirror)
			)
		)
		(property "Val" "220R"
			(at 0 0 90)
			(unlocked yes)
			(layer "B.Fab")
			(hide yes)
			(effects
				(font
					(size 1 1)
					(thickness 0.15)
				)
				(justify mirror)
			)
		)
		(property "Tolerance" "1%"
			(at 0 0 90)
			(unlocked yes)
			(layer "B.Fab")
			(hide yes)
			(effects
				(font
					(size 1 1)
					(thickness 0.15)
				)
				(justify mirror)
			)
		)
		(sheetname "/2xRJ45/")
		(sheetfile "2xrj45.kicad_sch")
		(attr smd)
		(fp_rect
			(start -0.925 0.47)
			(end 0.925 -0.47)
			(stroke
				(width 0.05)
				(type default)
			)
			(fill no)
			(layer "B.CrtYd")
		)
		(fp_rect
			(start -0.5 0.25)
			(end 0.5 -0.25)
			(stroke
				(width 0.15)
				(type solid)
			)
			(fill no)
			(layer "B.Fab")
		)
		(fp_text user "Author: Antmicro"
			(at -0.95 -4.169 270)
			(layer "B.Fab")
			(effects
				(font
					(size 0.7 0.7)
					(thickness 0.15)
				)
				(justify left bottom mirror)
			)
		)
		(fp_text user "${REFERENCE}"
			(at -0.95 -3.168 270)
			(layer "B.Fab")
			(effects
				(font
					(size 0.7 0.7)
					(thickness 0.15)
				)
				(justify left bottom mirror)
			)
		)
		(fp_text user "License: Apache-2.0"
			(at -0.95 -5.169 270)
			(layer "B.Fab")
			(effects
				(font
					(size 0.7 0.7)
					(thickness 0.15)
				)
				(justify left bottom mirror)
			)
		)
		(pad "1" smd roundrect
			(at -0.48 0 90)
			(size 0.59 0.64)
			(layers "B.Cu" "B.Mask" "B.Paste")
			(roundrect_rratio 0.25)
			(net 407 "Net-(J4-LED_YG_Y-)")
			(pintype "passive")
		)
		(pad "2" smd roundrect
			(at 0.48 0 90)
			(size 0.59 0.64)
			(layers "B.Cu" "B.Mask" "B.Paste")
			(roundrect_rratio 0.25)
			(net 65 "/2xRJ45/~{P1_LINK_LESS_THAN_10G}")
			(pintype "passive")
		)
	)
)
